# TIMECARD (Time Appliance Project (Time Card)) — schematic netlist excerpt (pin names and nets, part order shuffled) for the footprints in the layout excerpt that follows; sources: Cadence DE-HDL packaged netlist, KiCad conversion of R4006-B0001-02_R01.brd

R367  RESISTOR  49.9OHM 1%  pkg SMC_0402R_H016  page 23 : \1\ = BF_ANT3_IN ; \2\ = ANT3_IN
ME3  NUT  pkg P_NUT_166CT244CB198_V1_H380  page 34 : \1\ = SG

(kicad_pcb
	(version 20260206)
	(generator "pcbnew")
	(generator_version "10.0")
	(general
		(thickness 1.6)
		(legacy_teardrops no)
	)
	(paper "A4")
	(title_block
		(title "timecard-production-celestica-r4006 — R4006-B0001-02_R01.brd")
		(comment 1 "Time Appliance Project (Time Card) / footprints 112-113 of 1113")
	)
	(layers
		(0 "F.Cu" signal "TOP")
		(4 "In1.Cu" signal "L02_GND1")
		(6 "In2.Cu" signal "L03_SIG1")
		(8 "In3.Cu" signal "L04_GND2")
		(10 "In4.Cu" signal "L05_VCC1")
		(12 "In5.Cu" signal "L06_VCC2")
		(14 "In6.Cu" signal "L07_GND3")
		(16 "In7.Cu" signal "L08_SIG2")
		(18 "In8.Cu" signal "L09_GND4")
		(2 "B.Cu" signal "BOTTOM")
		(9 "F.Adhes" user "F.Adhesive")
		(11 "B.Adhes" user "B.Adhesive")
		(13 "F.Paste" user "Package Geometry/Pastemask Top")
		(15 "B.Paste" user "Package Geometry/Pastemask Bottom")
		(5 "F.SilkS" user "Ref Des/Silkscreen Top")
		(7 "B.SilkS" user "Ref Des/Silkscreen Bottom")
		(1 "F.Mask" user "Board Geometry/Soldermask Top")
		(3 "B.Mask" user "Board Geometry/Soldermask Bottom")
		(17 "Dwgs.User" user "User.Drawings")
		(19 "Cmts.User" user "User.Comments")
		(21 "Eco1.User" user "User.Eco1")
		(23 "Eco2.User" user "User.Eco2")
		(25 "Edge.Cuts" user "Board Geometry/Outline")
		(27 "Margin" user)
		(31 "F.CrtYd" user "Package Geometry/Place Bound Top")
		(29 "B.CrtYd" user "Package Geometry/Place Bound Bottom")
		(35 "F.Fab" user "Ref Des/Assembly Top")
		(33 "B.Fab" user "Ref Des/Assembly Bottom")
	)
	(footprint ""
		(layer "F.Cu")
		(at 125.499876 -104.650032)
		(property "Reference" "ME3"
			(at -5.929376 -0.085598 0)
			(unlocked yes)
			(layer "F.SilkS")
			(effects
				(font
					(size 0.7874 0.5842)
					(thickness 0.1524)
				)
				(justify left)
			)
		)
		(property "Value" ""
			(at 0 0 0)
			(layer "F.Fab")
			(effects
				(font
					(size 1.27 1.27)
				)
			)
		)
		(property "Device Type" "NUT-G340-10437-01"
			(at -1.4732 4.226306 0)
			(unlocked yes)
			(layer "F.Fab")
			(hide yes)
			(effects
				(font
					(size 0.7874 0.5842)
					(thickness 0.1524)
				)
				(justify left)
			)
		)
		(property "User Part Number" "PARTNUM*"
			(at -3.048 5.242306 0)
			(unlocked yes)
			(layer "Cmts.User")
			(hide yes)
			(effects
				(font
					(size 0.7874 0.5842)
					(thickness 0.1524)
				)
				(justify left)
			)
		)
		(duplicate_pad_numbers_are_jumpers no)
		(fp_circle
			(center 0 0)
			(end 3.3528 0)
			(stroke
				(width 0.1)
				(type default)
			)
			(fill no)
			(layer "F.SilkS")
		)
		(fp_poly
			(pts
				(arc
					(start -2.102612 -0.1524)
					(mid -1.490671 -1.490671)
					(end -0.1524 -2.102612)
				)
				(arc
					(start -0.1524 -3.171444)
					(mid -2.245137 -2.245137)
					(end -3.171444 -0.1524)
				)
			)
			(stroke
				(width 0)
				(type default)
			)
			(fill yes)
			(layer "F.Paste")
		)
		(fp_poly
			(pts
				(arc
					(start -0.1524 2.102612)
					(mid -1.490671 1.490671)
					(end -2.102612 0.1524)
				)
				(arc
					(start -3.171444 0.1524)
					(mid -2.245137 2.245137)
					(end -0.1524 3.171444)
				)
			)
			(stroke
				(width 0)
				(type default)
			)
			(fill yes)
			(layer "F.Paste")
		)
		(fp_poly
			(pts
				(arc
					(start 0.1524 -2.102612)
					(mid 1.490671 -1.490671)
					(end 2.102612 -0.1524)
				)
				(arc
					(start 3.171444 -0.1524)
					(mid 2.245137 -2.245137)
					(end 0.1524 -3.171444)
				)
			)
			(stroke
				(width 0)
				(type default)
			)
			(fill yes)
			(layer "F.Paste")
		)
		(fp_poly
			(pts
				(arc
					(start 2.102612 0.1524)
					(mid 1.490671 1.490671)
					(end 0.1524 2.102612)
				)
				(arc
					(start 0.1524 3.171444)
					(mid 2.245137 2.245137)
					(end 3.171444 0.1524)
				)
			)
			(stroke
				(width 0)
				(type default)
			)
			(fill yes)
			(layer "F.Paste")
		)
		(fp_rect
			(start -7.5946 7.5946)
			(end 7.5946 -7.5946)
			(stroke
				(width 0)
				(type default)
			)
			(fill no)
			(layer "B.CrtYd")
		)
		(fp_poly
			(pts
				(arc
					(start 3.6068 0)
					(mid -3.6068 0)
					(end 3.6068 0)
				)
			)
			(stroke
				(width 0)
				(type default)
			)
			(fill no)
			(layer "F.CrtYd")
		)
		(fp_circle
			(center 0 0)
			(end 2.8448 0)
			(stroke
				(width 0.1)
				(type default)
			)
			(fill no)
			(layer "F.Fab")
		)
		(pad "1" thru_hole circle
			(at 0 0)
			(size 6.1976 6.1976)
			(drill 4.2164)
			(layers "*.Cu" "*.Mask")
			(remove_unused_layers no)
			(net "SG")
			(padstack
				(mode front_inner_back)
				(layer "Inner"
					(shape circle)
					(size 5.0292 5.0292)
					(clearance -0.1143)
				)
				(layer "B.Cu"
					(shape circle)
					(size 5.0292 5.0292)
				)
			)
		)
	)
	(footprint ""
		(layer "F.Cu")
		(at 12.192 -37.211 90)
		(property "Reference" "R367"
			(at -1.27 -3.26263 90)
			(unlocked yes)
			(layer "F.SilkS")
			(effects
				(font
					(size 0.7874 0.5842)
					(thickness 0.1524)
				)
			)
		)
		(property "Value" "VAL*"
			(at 0.02032 2.13233 90)
			(unlocked yes)
			(layer "F.Fab")
			(hide yes)
			(effects
				(font
					(size 0.7874 0.5842)
					(thickness 0.1524)
				)
			)
		)
		(property "Tolerance" "TOL*"
			(at 0.044704 3.05435 90)
			(unlocked yes)
			(layer "Cmts.User")
			(hide yes)
			(effects
				(font
					(size 0.7874 0.5842)
					(thickness 0.1524)
				)
			)
		)
		(property "User Part Number" "PARTNUM*"
			(at 0.02032 4.024884 90)
			(unlocked yes)
			(layer "Cmts.User")
			(hide yes)
			(effects
				(font
					(size 0.7874 0.5842)
					(thickness 0.1524)
				)
			)
		)
		(property "Device Type" "RESISTOR-G155-149R9-01,49.9OHMA"
			(at 0.008382 1.210564 90)
			(unlocked yes)
			(layer "F.Fab")
			(hide yes)
			(effects
				(font
					(size 0.7874 0.5842)
					(thickness 0.1524)
				)
			)
		)
		(duplicate_pad_numbers_are_jumpers no)
		(fp_line
			(start 1.143 -0.5588)
			(end -1.143 -0.5588)
			(stroke
				(width 0.1)
				(type default)
			)
			(layer "F.SilkS")
		)
		(fp_line
			(start -1.143 -0.5588)
			(end -1.143 0.5588)
			(stroke
				(width 0.1)
				(type default)
			)
			(layer "F.SilkS")
		)
		(fp_line
			(start 1.143 0.5588)
			(end 1.143 -0.5588)
			(stroke
				(width 0.1)
				(type default)
			)
			(layer "F.SilkS")
		)
		(fp_line
			(start -1.143 0.5588)
			(end 1.143 0.5588)
			(stroke
				(width 0.1)
				(type default)
			)
			(layer "F.SilkS")
		)
		(fp_poly
			(pts
				(xy -1.143 0.5588) (xy 1.143 0.5588) (xy 1.143 -0.5588) (xy -1.143 -0.5588)
			)
			(stroke
				(width 0)
				(type default)
			)
			(fill no)
			(layer "F.CrtYd")
		)
		(fp_line
			(start 0.508 -0.3048)
			(end -0.508 -0.3048)
			(stroke
				(width 0.1)
				(type default)
			)
			(layer "F.Fab")
		)
		(fp_line
			(start -0.508 -0.3048)
			(end -0.508 0.3048)
			(stroke
				(width 0.1)
				(type default)
			)
			(layer "F.Fab")
		)
		(fp_line
			(start 0.508 0.3048)
			(end 0.508 -0.3048)
			(stroke
				(width 0.1)
				(type default)
			)
			(layer "F.Fab")
		)
		(fp_line
			(start -0.508 0.3048)
			(end 0.508 0.3048)
			(stroke
				(width 0.1)
				(type default)
			)
			(layer "F.Fab")
		)
		(pad "1" smd rect
			(at -0.5334 0 90)
			(size 0.7112 0.6096)
			(layers "F.Cu" "F.Mask" "F.Paste")
			(net "BF_ANT3_IN")
		)
		(pad "2" smd rect
			(at 0.5334 0 90)
			(size 0.7112 0.6096)
			(layers "F.Cu" "F.Mask" "F.Paste")
			(net "ANT3_IN")
		)
		(zone
			(layer "F.Cu")
			(hatch none 0.5)
			(connect_pads
				(clearance 0)
			)
			(min_thickness 0.25)
			(keepout
				(tracks allowed)
				(vias not_allowed)
				(pads allowed)
				(copperpour not_allowed)
				(footprints allowed)
			)
			(placement
				(enabled no)
				(sheetname "")
			)
			(fill
				(thermal_gap 0.5)
				(thermal_bridge_width 0.5)
				(island_removal_mode 0)
			)
			(polygon
				(pts
					(xy 12.4968 -37.1348) (xy 12.4968 -37.2872) (xy 11.8872 -37.2872) (xy 11.8872 -37.1348)
				)
			)
		)
		(zone
			(layer "F.Cu")
			(hatch none 0.5)
			(connect_pads
				(clearance 0)
			)
			(min_thickness 0.25)
			(keepout
				(tracks not_allowed)
				(vias allowed)
				(pads allowed)
				(copperpour not_allowed)
				(footprints allowed)
			)
			(placement
				(enabled no)
				(sheetname "")
			)
			(fill
				(thermal_gap 0.5)
				(thermal_bridge_width 0.5)
				(island_removal_mode 0)
			)
			(polygon
				(pts
					(xy 12.4968 -37.1348) (xy 12.4968 -37.2872) (xy 11.8872 -37.2872) (xy 11.8872 -37.1348)
				)
			)
		)
	)
)
